# T6G (Grand Teton) — schematic netlist excerpt (pin names and nets, part order shuffled) for the footprints in the layout excerpt that follows; sources: Cadence DE-HDL packaged netlist, KiCad conversion of 04192023_DAF0TMB3IC0_F0TG_MB_C_brd_V02_OCP.brd

R5009  Q_RES  1K 1% EMPTY  pkg 0402LF  page 159 : A = PVDD11_S3_P0 ; B = I3C_SPD_DDRGL_CPU0_LVC1_SDA
C2410  Q_CAP  22UF 4V 20% X6S  pkg C0402  page 74 : A = PVDDCR_SOC_P1 ; B = GND

(kicad_pcb
	(version 20260206)
	(generator "pcbnew")
	(generator_version "10.0")
	(general
		(thickness 1.6)
		(legacy_teardrops no)
	)
	(paper "A4")
	(title_block
		(title "04192023_DAF0TMB3IC0_F0TG_MB_C_brd_V02_OCP.brd")
		(comment 1 "Grand Teton / footprints 4243-4244 of 8354")
	)
	(layers
		(0 "F.Cu" signal "TOP")
		(4 "In1.Cu" signal "GND")
		(6 "In2.Cu" signal "IN1")
		(8 "In3.Cu" signal "GND1")
		(10 "In4.Cu" signal "IN2")
		(12 "In5.Cu" signal "GND2")
		(14 "In6.Cu" signal "IN3")
		(16 "In7.Cu" signal "GND3")
		(18 "In8.Cu" signal "VCC")
		(20 "In9.Cu" signal "VCC1")
		(22 "In10.Cu" signal "GND4")
		(24 "In11.Cu" signal "IN4")
		(26 "In12.Cu" signal "GND5")
		(28 "In13.Cu" signal "IN5")
		(30 "In14.Cu" signal "GND6")
		(32 "In15.Cu" signal "IN6")
		(34 "In16.Cu" signal "GND7")
		(2 "B.Cu" signal "BOTTOM")
		(9 "F.Adhes" user "F.Adhesive")
		(11 "B.Adhes" user "B.Adhesive")
		(13 "F.Paste" user "Package Geometry/Pastemask Top")
		(15 "B.Paste" user "Package Geometry/Pastemask Bottom")
		(5 "F.SilkS" user "Ref Des/Silkscreen Top")
		(7 "B.SilkS" user "Ref Des/Silkscreen Bottom")
		(1 "F.Mask" user "Board Geometry/Soldermask Top")
		(3 "B.Mask" user "Board Geometry/Soldermask Bottom")
		(17 "Dwgs.User" user "User.Drawings")
		(19 "Cmts.User" user "User.Comments")
		(21 "Eco1.User" user "User.Eco1")
		(23 "Eco2.User" user "User.Eco2")
		(25 "Edge.Cuts" user "Board Geometry/Outline")
		(27 "Margin" user)
		(31 "F.CrtYd" user "Package Geometry/Place Bound Top")
		(29 "B.CrtYd" user "Package Geometry/Place Bound Bottom")
		(35 "F.Fab" user "Ref Des/Assembly Top")
		(33 "B.Fab" user "Ref Des/Assembly Bottom")
	)
	(footprint ""
		(layer "F.Cu")
		(at 109.575854 -256.012442 90)
		(property "Reference" "C2410"
			(at 0 0 90)
			(layer "F.SilkS")
			(hide yes)
			(effects
				(font
					(size 1.27 1.27)
				)
			)
		)
		(property "Value" ""
			(at 0 0 90)
			(layer "F.Fab")
			(effects
				(font
					(size 1.27 1.27)
				)
			)
		)
		(duplicate_pad_numbers_are_jumpers no)
		(fp_line
			(start 0.7874 -0.4064)
			(end 0.7874 0.4064)
			(stroke
				(width 0.1524)
				(type default)
			)
			(layer "F.SilkS")
		)
		(fp_line
			(start -0.7874 -0.4064)
			(end 0.7874 -0.4064)
			(stroke
				(width 0.1524)
				(type default)
			)
			(layer "F.SilkS")
		)
		(fp_line
			(start 0.7874 0.4064)
			(end -0.7874 0.4064)
			(stroke
				(width 0.1524)
				(type default)
			)
			(layer "F.SilkS")
		)
		(fp_line
			(start -0.7874 0.4064)
			(end -0.7874 -0.4064)
			(stroke
				(width 0.1524)
				(type default)
			)
			(layer "F.SilkS")
		)
		(fp_line
			(start -0.12065 -0.305054)
			(end -0.12065 -0.2794)
			(stroke
				(width 0.1)
				(type default)
			)
			(layer "F.Fab")
		)
		(fp_line
			(start -0.67945 -0.305054)
			(end -0.12065 -0.305054)
			(stroke
				(width 0.1)
				(type default)
			)
			(layer "F.Fab")
		)
		(fp_line
			(start 0.67945 -0.3048)
			(end 0.67945 0.3048)
			(stroke
				(width 0.1)
				(type default)
			)
			(layer "F.Fab")
		)
		(fp_line
			(start 0.12065 -0.3048)
			(end 0.67945 -0.3048)
			(stroke
				(width 0.1)
				(type default)
			)
			(layer "F.Fab")
		)
		(fp_line
			(start 0.12065 -0.2794)
			(end 0.12065 -0.3048)
			(stroke
				(width 0.1)
				(type default)
			)
			(layer "F.Fab")
		)
		(fp_line
			(start -0.12065 -0.2794)
			(end 0.12065 -0.2794)
			(stroke
				(width 0.1)
				(type default)
			)
			(layer "F.Fab")
		)
		(fp_line
			(start 0.120396 0.2794)
			(end -0.12065 0.2794)
			(stroke
				(width 0.1)
				(type default)
			)
			(layer "F.Fab")
		)
		(fp_line
			(start -0.12065 0.2794)
			(end -0.12065 0.3048)
			(stroke
				(width 0.1)
				(type default)
			)
			(layer "F.Fab")
		)
		(fp_line
			(start 0.67945 0.3048)
			(end 0.120396 0.3048)
			(stroke
				(width 0.1)
				(type default)
			)
			(layer "F.Fab")
		)
		(fp_line
			(start 0.120396 0.3048)
			(end 0.120396 0.2794)
			(stroke
				(width 0.1)
				(type default)
			)
			(layer "F.Fab")
		)
		(fp_line
			(start -0.12065 0.3048)
			(end -0.67945 0.3048)
			(stroke
				(width 0.1)
				(type default)
			)
			(layer "F.Fab")
		)
		(fp_line
			(start -0.67945 0.3048)
			(end -0.67945 -0.305054)
			(stroke
				(width 0.1)
				(type default)
			)
			(layer "F.Fab")
		)
		(pad "1" smd circle
			(at -0.40005 0 90)
			(size 0 0)
			(layers "F.Cu" "F.Mask" "F.Paste")
			(net "PVDDCR_SOC_P1")
		)
		(pad "2" smd circle
			(at 0.40005 0 90)
			(size 0 0)
			(layers "F.Cu" "F.Mask" "F.Paste")
			(net "GND")
		)
	)
	(footprint ""
		(layer "F.Cu")
		(at 434.678836 -169.224452)
		(property "Reference" "R5009"
			(at 0 0 0)
			(layer "F.SilkS")
			(hide yes)
			(effects
				(font
					(size 1.27 1.27)
				)
			)
		)
		(property "Value" ""
			(at 0 0 0)
			(layer "F.Fab")
			(effects
				(font
					(size 1.27 1.27)
				)
			)
		)
		(duplicate_pad_numbers_are_jumpers no)
		(fp_line
			(start -0.7874 -0.4064)
			(end 0.7874 -0.4064)
			(stroke
				(width 0.1524)
				(type default)
			)
			(layer "F.SilkS")
		)
		(fp_line
			(start -0.7874 0.4064)
			(end -0.7874 -0.4064)
			(stroke
				(width 0.1524)
				(type default)
			)
			(layer "F.SilkS")
		)
		(fp_line
			(start 0.7874 -0.4064)
			(end 0.7874 0.4064)
			(stroke
				(width 0.1524)
				(type default)
			)
			(layer "F.SilkS")
		)
		(fp_line
			(start 0.7874 0.4064)
			(end -0.7874 0.4064)
			(stroke
				(width 0.1524)
				(type default)
			)
			(layer "F.SilkS")
		)
		(fp_line
			(start -0.67945 -0.305054)
			(end -0.12065 -0.305054)
			(stroke
				(width 0.1)
				(type default)
			)
			(layer "F.Fab")
		)
		(fp_line
			(start -0.67945 0.3048)
			(end -0.67945 -0.305054)
			(stroke
				(width 0.1)
				(type default)
			)
			(layer "F.Fab")
		)
		(fp_line
			(start -0.12065 -0.305054)
			(end -0.12065 -0.2794)
			(stroke
				(width 0.1)
				(type default)
			)
			(layer "F.Fab")
		)
		(fp_line
			(start -0.12065 -0.2794)
			(end 0.12065 -0.2794)
			(stroke
				(width 0.1)
				(type default)
			)
			(layer "F.Fab")
		)
		(fp_line
			(start -0.12065 0.2794)
			(end -0.12065 0.3048)
			(stroke
				(width 0.1)
				(type default)
			)
			(layer "F.Fab")
		)
		(fp_line
			(start -0.12065 0.3048)
			(end -0.67945 0.3048)
			(stroke
				(width 0.1)
				(type default)
			)
			(layer "F.Fab")
		)
		(fp_line
			(start 0.120396 0.2794)
			(end -0.12065 0.2794)
			(stroke
				(width 0.1)
				(type default)
			)
			(layer "F.Fab")
		)
		(fp_line
			(start 0.120396 0.3048)
			(end 0.120396 0.2794)
			(stroke
				(width 0.1)
				(type default)
			)
			(layer "F.Fab")
		)
		(fp_line
			(start 0.12065 -0.3048)
			(end 0.67945 -0.3048)
			(stroke
				(width 0.1)
				(type default)
			)
			(layer "F.Fab")
		)
		(fp_line
			(start 0.12065 -0.2794)
			(end 0.12065 -0.3048)
			(stroke
				(width 0.1)
				(type default)
			)
			(layer "F.Fab")
		)
		(fp_line
			(start 0.67945 -0.3048)
			(end 0.67945 0.3048)
			(stroke
				(width 0.1)
				(type default)
			)
			(layer "F.Fab")
		)
		(fp_line
			(start 0.67945 0.3048)
			(end 0.120396 0.3048)
			(stroke
				(width 0.1)
				(type default)
			)
			(layer "F.Fab")
		)
		(pad "1" smd circle
			(at -0.40005 0)
			(size 0 0)
			(layers "F.Cu" "F.Mask" "F.Paste")
			(net "PVDD11_S3_P0")
		)
		(pad "2" smd circle
			(at 0.40005 0)
			(size 0 0)
			(layers "F.Cu" "F.Mask" "F.Paste")
			(net "I3C_SPD_DDRGL_CPU0_LVC1_SDA")
		)
	)
)
